# TIMECARD (Time Appliance Project (Time Card)) — schematic parts with pin connectivity, parts 1098–1119 of 1119; source: Cadence DE-HDL packaged netlist (pstxprt.dat, pstxnet.dat, pstchip.dat)

U24  XC7A200T_2FBG484C_FBG484  XC7A100T-1FGG484I  pkg BGA484_906_P0394_V3  page 10  (pins 349-484 of 484)
  P19  IO_L5P_T0_D06_14  BI  = NC
  P20  IO_0_14  BI  = UART_GPS_RX_FPGA_TX
  P21  IO_L2P_T0_D02_14  BI  = FPGA_D02
  P22  IO_L1P_T0_D00_MOSI_14  BI  = FPGA_D00_MOSI
  R1  IO_L20P_T3_35  BI  = IO_L20P_35
  R2  IO_L3N_T0_DQS_34  BI  = NC
  R3  IO_L3P_T0_DQS_34  BI  = NC
  R4  IO_L13P_T2_MRCC_34  BI  = MHZ200CLKP_CLKIN
  R5  VCCO_34_3  POWER  = XP2R5V_FPGA
  R6  IO_L17P_T2_34  BI  = NC
  R7  VCCINT_11  POWER  = XP1R0V_FPGA_VCCINT
  R8  GND_74  GROUND  = SG
  R9  VCCINT_12  POWER  = XP1R0V_FPGA_VCCINT
  R10  GND_71  GROUND  = SG
  R11  VCCAUX_5  POWER  = XP1R8V_FPGA_VCCAUX
  R12  GND_72  GROUND  = SG
  R13  TDI_0  IN  = FPGA_TDI
  R14  IO_L19N_T3_A09_D25_VREF_14  BI  = MAC_USB_DM
  R15  VCCO_14_3  POWER  = XP3R3V_FPGA
  R16  IO_L22N_T3_A04_D20_14  BI  = NC
  R17  IO_L24N_T3_A00_D16_14  BI  = NC
  R18  IO_L20P_T3_A08_D24_14  BI  = NC
  R19  IO_L5N_T0_D07_14  BI  = NC
  R20  GND_73  GROUND  = SG
  R21  IO_L2N_T0_D03_14  BI  = FPGA_D03
  R22  IO_L1N_T0_D01_DIN_14  BI  = FPGA_D01
  T1  IO_L1P_T0_34  BI  = NC
  T2  VCCO_34_4  POWER  = XP2R5V_FPGA
  T3  IO_0_34  BI  = NC
  T4  IO_L13N_T2_MRCC_34  BI  = MHZ200CLKN_CLKIN
  T5  IO_L14P_T2_SRCC_34  BI  = NC
  T6  IO_L17N_T2_34  BI  = NC
  T7  GND_77  GROUND  = SG
  T8  VCCINT_14  POWER  = XP1R0V_FPGA_VCCINT
  T9  GND_78  GROUND  = SG
  T10  VCCINT_13  POWER  = XP1R0V_FPGA_VCCINT
  T11  GND_75  GROUND  = SG
  T12  VCCO_0_2  POWER  = XP3R3V_FPGA
  T13  TMS_0  IN  = FPGA_TMS
  T14  IO_L15P_T2_DQS_13  BI  = NC
  T15  IO_L15N_T2_DQS_13  BI  = NC
  T16  IO_L17P_T2_13  BI  = FPGA_PCA9546_I2C_SDA
  T17  GND_76  GROUND  = SG
  T18  IO_L20N_T3_A07_D23_14  BI  = NC
  T19  IO_L6P_T0_FCS_B_14  BI  = FPGA_FCS_B
  T20  IO_L6N_T0_D08_VREF_14  BI  = NC
  T21  IO_L4P_T0_D04_14  BI  = NC
  T22  VCCO_14_4  POWER  = XP3R3V_FPGA
  U1  IO_L1N_T0_34  BI  = NC
  U2  IO_L2P_T0_34  BI  = NC
  U3  IO_L6P_T0_34  BI  = NC
  U4  GND_80  GROUND  = SG
  U5  IO_L14N_T2_SRCC_34  BI  = NC
  U6  IO_L16P_T2_34  BI  = NC
  U7  IO_25_34  BI  = NC
  U8  CFGBVS_0  IN  = CFGBVS
  U9  M2_0  IN  = FPGA_M2
  U10  M1_0  IN  = FPGA_M1
  U11  M0_0  IN  = FPGA_M0
  U12  \init_0*\  BI  = FPGA_CFG_INIT_N
  U13  TDO_0  OUT  = R_FPGA_TDO
  U14  GND_79  GROUND  = SG
  U15  IO_L14P_T2_SRCC_13  BI  = NC
  U16  IO_L17N_T2_13  BI  = FPGA_OUT_PCA9546_RST_N
  U17  IO_L18P_T2_A12_D28_14  BI  = NC
  U18  IO_L18N_T2_A11_D27_14  BI  = NC
  U19  VCCO_14_5  POWER  = XP3R3V_FPGA
  U20  IO_L11P_T1_SRCC_14  BI  = NC
  U21  IO_L4N_T0_D05_14  BI  = NC
  U22  \io_l3p_t0_dqs_pudc_14*\  BI  = PUDC
  V1  GND_81  GROUND  = SG
  V2  IO_L2N_T0_34  BI  = NC
  V3  IO_L6N_T0_VREF_34  BI  = NC
  V4  IO_L12P_T1_MRCC_34  BI  = NC
  V5  IO_L16N_T2_34  BI  = NC
  V6  VCCO_34_5  POWER  = XP2R5V_FPGA
  V7  IO_L19P_T3_34  BI  = NC
  V8  IO_L21N_T3_DQS_34  BI  = IO_L21N_34
  V9  IO_L21P_T3_DQS_34  BI  = IO_L21P_34
  V10  IO_L10P_T1_13  BI  = ANT1_OUT
  V11  GND_82  GROUND  = SG
  V12  TCK_0  IN  = FPGA_TCK
  V13  IO_L13P_T2_MRCC_13  BI  = FPGA_IN_MAC_10MHZ_OUT
  V14  IO_L13N_T2_MRCC_13  BI  = NC
  V15  IO_L14N_T2_SRCC_13  BI  = FPGA_OUT_MACUSBPOWER_EN
  V16  VCCO_13_3  POWER  = XP3R3V_FPGA
  V17  \io_l16p_t2_csi_14*\  BI  = NC
  V18  IO_L14P_T2_SRCC_14  BI  = NC
  V19  IO_L14N_T2_SRCC_14  BI  = NC
  V20  IO_L11N_T1_SRCC_14  BI  = NC
  V21  GND_83  GROUND  = SG
  V22  IO_L3N_T0_DQS_EMCCLK_14  BI  = NC
  W1  IO_L5P_T0_34  BI  = FPGA_IN_MAC_PPS_OUTP
  W2  IO_L4P_T0_34  BI  = NC
  W3  VCCO_34_6  POWER  = XP2R5V_FPGA
  W4  IO_L12N_T1_MRCC_34  BI  = NC
  W5  IO_L15N_T2_DQS_34  BI  = NC
  W6  IO_L15P_T2_DQS_34  BI  = NC
  W7  IO_L19N_T3_VREF_34  BI  = NC
  W8  GND_85  GROUND  = SG
  W9  IO_L24P_T3_34  BI  = IO_L24P_34
  W10  IO_L10N_T1_13  BI  = ANT2_OUT
  W11  IO_L12P_T1_MRCC_13  BI  = ANT3_OUT
  W12  IO_L12N_T1_MRCC_13  BI  = ANT4_OUT
  W13  VCCO_13_4  POWER  = XP3R3V_FPGA
  W14  IO_L6P_T0_13  BI  = FPGA_IN_GPSTP1_OUT
  W15  IO_L16P_T2_13  BI  = NC
  W16  IO_L16N_T2_13  BI  = NC
  W17  IO_L16N_T2_A15_D31_14  BI  = NC
  W18  GND_84  GROUND  = SG
  W19  IO_L12P_T1_MRCC_14  BI  = FPGA_M_RGB_LED_I2C_SDA
  W20  IO_L12N_T1_MRCC_14  BI  = FPGA_M_RGB_LED_I2C_SCL
  W21  IO_L7P_T1_D09_14  BI  = NC
  W22  IO_L7N_T1_D10_14  BI  = NC
  Y1  IO_L5N_T0_34  BI  = FPGA_IN_MAC_PPS_OUTN
  Y2  IO_L4N_T0_34  BI  = NC
  Y3  IO_L9P_T1_DQS_34  BI  = NC
  Y4  IO_L11P_T1_SRCC_34  BI  = NC
  Y5  GND_87  GROUND  = SG
  Y6  IO_L18P_T2_34  BI  = NC
  Y7  IO_L23N_T3_34  BI  = IO_L23N_34
  Y8  IO_L23P_T3_34  BI  = IO_L23P_34
  Y9  IO_L24N_T3_34  BI  = IO_L24N_34
  Y10  VCCO_13_5  POWER  = XP3R3V_FPGA
  Y11  IO_L11P_T1_SRCC_13  BI  = ANT3_IN
  Y12  IO_L11N_T1_SRCC_13  BI  = ANT4_IN
  Y13  IO_L5P_T0_13  BI  = NC
  Y14  IO_L6N_T0_VREF_13  BI  = FPGA_IN_GPSTP2_OUT
  Y15  GND_86  GROUND  = SG
  Y16  IO_L1P_T0_13  BI  = FPGA_OUT_GPS_RST_N
  Y17  IO_0_13  BI  = NC
  Y18  IO_L13P_T2_MRCC_14  BI  = FPGA_OUT_RGB_LED_SHUTDOWN_N
  Y19  IO_L13N_T2_MRCC_14  BI  = NC
  Y20  VCCO_14_6  POWER  = XP3R3V_FPGA
  Y21  IO_L9P_T1_DQS_14  BI  = NC
  Y22  IO_L9N_T1_DQS_D13_14  BI  = NC

U25  ISL80101IRAJZ_DFN10  pkg DFN11_118_P0197_TR057X071  page 31
  1  VOUT_1  OUT  = XP2R5V_FPGA
  2  VOUT_2  OUT  = XP2R5V_FPGA
  3  \sense/adj\  BI  = UNNAMED_515_ISL80101IRAJZDFN10_
  4  PG  BI  = UNNAMED_515_CAPACITOR_I138_1
  5  GND  GROUND  = SG
  6  SS  BI  = UNNAMED_515_CAPACITOR_I132_1
  7  ENABLE  BI  = UNNAMED_515_CAPACITOR_I128_1
  8  NC  NC  = NC
  9  VIN_1  IN  = UNNAMED_515_CAPACITOR_I130_1
  10  VIN_2  IN  = UNNAMED_515_CAPACITOR_I130_1
  11  THRM_PAD  GROUND  = SG

U26  TPS54824RNVR_VQFN18  TPS54424RNVT  pkg QFN18_138_P0197_V1  page 29
  1  BOOT  IN  = XP1R0V_BT
  2  VIN_1  IN  = VIN_XP1R0V
  3  PGND_1  GROUND  = SG
  4  PGND_2  GROUND  = SG
  5  PGND_3  GROUND  = SG
  6  SW_1  OUT  = XP1R0V_SW
  7  SW_2  OUT  = XP1R0V_SW
  8  PGND_4  GROUND  = SG
  9  PGND_5  GROUND  = SG
  10  PGND_6  GROUND  = SG
  11  VIN_2  POWER  = VIN_XP1R0V
  12  AGND  GROUND  = XP1R0V_AGND
  13  \rt/clk\  IN  = XP1R0V_RT
  14  FB  IN  = XP1R0V_FB_R_TO_AGND
  15  COMP  IN  = XP1R0V_COMP
  16  \ss/trk\  IN  = XP1R0V_SS
  17  EN  IN  = UNNAMED_523_CAPACITOR_I7_1
  18  PGOOD  OUT  = XP1R0V_PG

U27  SHT31A_DIS_B10KS_DFN8  SHT31A-DIS-B10KS  pkg DFN9_098_P0197_TR039X071  page 18
  1  SDA  BI  = R_SHT3X_I2C_SDA
  2  ADDR  IN  = SHT3X_ADDR
  3  ALERT  OUT  = R_SHT3X_ALERT_N
  4  SCL  BI  = R_SHT3X_I2C_SCL
  5  VDD  POWER  = VDD3V3_SHT31A
  6  \reset*\  IN  = R_SHT3X_RST_N
  7  R  BI  = SG
  8  VSS  GROUND  = SG
  9  THRM_PAD  GROUND  = SG

U28  ICP_10100_LGA10  ICP-10100  pkg LGA10_079_P0197  page 19
  1  RESV_1  BI  = UNNAMED_8_ICP10100LGA10_I24_RES
  2  SCL  BI  = R_ICP10100_I2C_SCL
  3  RESV_2  BI  = UNNAMED_8_ICP10100LGA10_I24_R_1
  4  SDA  BI  = R_ICP10100_I2C_SDA
  5  RESV_3  BI  = UNNAMED_8_ICP10100LGA10_I24_R_2
  6  RESV_4  BI  = UNNAMED_8_ICP10100LGA10_I24_R_3
  7  RESV_5  BI  = UNNAMED_8_ICP10100LGA10_I24_R_4
  8  GND_1  GROUND  = SG
  9  GND_2  GROUND  = SG
  10  VDD  POWER  = XP1R8V_ICP10100

U29  BNO080_LGA_28  BNO085  pkg LGA28_205X150_P0197  page 20
  1  RESV_NC_1  NC  = NC
  2  GND_1  GROUND  = SG
  3  VDD  IN  = VDD_BNO085
  4  BOOTN  IN  = R_BNO080_BOOT_N
  5  PS1  IN  = UNNAMED_9_BNO080LGA28_I29_PS1
  6  \ps0/wake\  IN  = UNNAMED_9_BNO080LGA28_I29_PS0
  7  RESV_NC_2  IN  = NC
  8  RESV_NC_3  NC  = NC
  9  CAP  BI  = UNNAMED_9_BNO080LGA28_I29_CAP
  10  CLKSEL0  IN  = UNNAMED_9_BNO080LGA28_I29_CLKSE
  11  \rst*\  IN  = R_BNO080_RST_N
  12  RESV_NC_4  NC  = NC
  13  RESV_NC_5  NC  = NC
  14  H_INTN  OUT  = R_BNO080_INT_N
  15  ENV_SCL  BI  = R_BNO080_EVN_SCL
  16  ENV_SDA  BI  = R_BNO080_EVN_SDA
  17  \sa0/h_mosi\  IN  = BNO080_SA0
  18  \h_cs*\  IN  = UNNAMED_9_BNO080LGA28_I29_HCS
  19  \h_scl/sck/rx\  BI  = R_BNO080_I2C_SCL
  20  \h_sda/h_miso/tx\  BI  = R_BNO080_I2C_SDA
  21  RESV_NC_6  NC  = NC
  22  RESV_NC_7  NC  = NC
  23  RESV_NC_8  NC  = NC
  24  RESV_NC_9  NC  = NC
  25  GND_2  GROUND  = SG
  26  \xout32/clksel1\  OUT  = UNNAMED_9_BNO080LGA28_I29_XOUT3
  27  XIN32  IN  = UNNAMED_9_CAPACITOR_I17_1
  28  VDDIO  IN  = VDD_BNO085

U30  TS3A5018PWR_TSSOP16  pkg SOP16_173_P0256  page 24
  1  \in\  BI  = MUX1_SEL
  2  NC1  BI  = FT4232_FPGA_TCK
  3  NO1  BI  = FT4232_SPI_CLK
  4  COM1  BI  = FT4232_TCK_SCLK
  5  NC2  BI  = FT4232_FPGA_TDI
  6  NO2  BI  = FT4232_SPI_MOSI
  7  COM2  BI  = FT4232_TDI_MOSI
  8  GND  GROUND  = SG
  9  COM3  BI  = FT4232_TDO_MISO
  10  NO3  BI  = FT4232_SPI_MISO
  11  NC3  BI  = FT4232_FPGA_TDO
  12  COM4  BI  = FT4232_TMS_SPICS_N
  13  NO4  BI  = FT4232_SPI_CS_N
  14  NC4  BI  = FT4232_FPGA_TMS
  15  \en*\  BI  = UNNAMED_524_POWERMOS3PNCHV1_I44
  16  V_P  POWER  = XP3R3V_FPGA

U31  CAT93C46VI_GT3_SOIC8  pkg SOP8_154_P050_V1  page 24
  1  CS  BI  = FTDI_EE_CS
  2  SK  IN  = FTDI_EE_CLK
  3  DI  IN  = FTDI_EE_DAT
  4  DO  OUT  = FTDI_EE_DO
  5  GND  GROUND  = SG
  6  ORG  BI  = XP3R3V_FT4232
  7  NC  NC  = NC
  8  VCC  POWER  = XP3R3V_FT4232

U32  PCA9508DP_TSSOP8  pkg SOP8_118_P0256_V2  page 19
  1  VCC_A  POWER  = XP1R8V_ICP10100
  2  SCLA  BI  = BF_ICP10100_I2C_SCL
  3  SDAA  BI  = BF_ICP10100_I2C_SDA
  4  GND  GROUND  = SG
  5  EN  IN  = UNNAMED_8_PCA9508DPTSSOP8_I51_E
  6  SDAB  BI  = ICP10100_I2C_SDA
  7  SCLB  BI  = ICP10100_I2C_SCL
  8  VCC_B  POWER  = XP3R3V

U33  IS32FL3207_QWLA3_TR_QFN29  IS32FL3207-QWLA3-TR  pkg QFN29_197_P0197_TR115SQ_V1  page 26
  1  \sdb*\  BI  = RGB_LED_SHUTDOWN_N
  2  AD  BI  = UNNAMED_14_IS32FL3207QWLA3TRQFN
  3  VCC  POWER  = XP3R3V_FPGA
  4  GND_1  GROUND  = SG
  5  ISET  BI  = UNNAMED_14_IS32FL3207QWLA3TRQ_1
  6  SDA  BI  = R_RGB_LED_I2C_SDA
  7  SCL  BI  = R_RGB_LED_I2C_SCL
  8  OUT1  OUT  = SMA1_LED_GREEN_N
  9  OUT2  OUT  = SMA1_LED_RED_N
  10  OUT3  OUT  = SMA1_LED_BLUE_N
  11  GND_2  GROUND  = SG
  12  OUT4  OUT  = SMA2_LED_GREEN_N
  13  OUT5  OUT  = SMA2_LED_RED_N
  14  OUT6  OUT  = SMA2_LED_BLUE_N
  15  OUT7  OUT  = SMA3_LED_GREEN_N
  16  OUT8  OUT  = SMA3_LED_RED_N
  17  OUT9  OUT  = SMA3_LED_BLUE_N
  18  GND_3  GROUND  = SG
  19  OUT10  OUT  = SMA4_LED_GREEN_N
  20  OUT11  OUT  = SMA4_LED_RED_N
  21  OUT12  OUT  = SMA4_LED_BLUE_N
  22  OUT13  OUT  = GPS_SMA_LED_GREEN_N
  23  OUT14  OUT  = GPS_SMA_LED_RED_N
  24  OUT15  OUT  = GPS_SMA_LED_BLUE_N
  25  GND_4  GROUND  = SG
  26  OUT16  OUT  = NC
  27  OUT17  OUT  = NC
  28  OUT18  OUT  = NC
  29  THRM_PAD  GROUND  = SG

U34  TPS3808G18DBVR_SOT23_6  pkg SOT23_6  page 9
  1  \reset*\  OUT  = FPGA_IN_RST_DLY_N
  2  GND  GROUND  = SG
  3  \mr*\  BI  = PCIE_PERST_N
  4  CT  BI  = UNNAMED_3_RESISTOR_I151_2
  5  SENSE  BI  = XP3R3V_FPGA
  6  VDD  POWER  = XP3R3V_FPGA

U35  LM75BDP_TSSOP8  pkg SOP8_118_P0256_V2  page 17
  1  SDA  BI  = R_LM75B_2_I2C_SDA
  2  SCL  IN  = LM75B_I2C_SCL
  3  OS  OUT  = FPGA_IN_LM75B_INT2_N
  4  GND  GROUND  = SG
  5  A2  IN  = UNNAMED_6_LM75BDPTSSOP8_I59_A2
  6  A1  IN  = UNNAMED_6_LM75BDPTSSOP8_I59_A1
  7  A0  IN  = UNNAMED_6_LM75BDPTSSOP8_I59_A0
  8  VCC  POWER  = XP3R3V_FPGA

U36  LM75BDP_TSSOP8  pkg SOP8_118_P0256_V2  page 17
  1  SDA  BI  = R_LM75B_3_I2C_SDA
  2  SCL  IN  = LM75B_I2C_SCL
  3  OS  OUT  = FPGA_IN_LM75B_INT3_N
  4  GND  GROUND  = SG
  5  A2  IN  = UNNAMED_6_LM75BDPTSSOP8_I81_A2
  6  A1  IN  = UNNAMED_6_LM75BDPTSSOP8_I81_A1
  7  A0  IN  = UNNAMED_6_LM75BDPTSSOP8_I81_A0
  8  VCC  POWER  = XP3R3V_FPGA

U37  TS3A5018PWR_TSSOP16  pkg SOP16_173_P0256  page 24
  1  \in\  BI  = MUX3_SEL
  2  NC1  BI  = FPGA_PCA9546_I2C_SDA
  3  NO1  BI  = FT4232_I2C_SDA
  4  COM1  BI  = PCA9546_I2C_SDA
  5  NC2  BI  = FPGA_PCA9546_I2C_SCL
  6  NO2  BI  = FT4232_I2C_SCL
  7  COM2  BI  = PCA9546_I2C_SCL
  8  GND  GROUND  = SG
  9  COM3  BI  = EEPROM_I2C_SDA
  10  NO3  BI  = FT4232_I2C_SDA
  11  NC3  BI  = FPGA_EEPROM_I2C_SDA
  12  COM4  BI  = EEPROM_I2C_SCL
  13  NO4  BI  = FT4232_I2C_SCL
  14  NC4  BI  = FPGA_EEPROM_I2C_SCL
  15  \en*\  BI  = UNNAMED_524_RESISTOR_I463_2
  16  V_P  POWER  = XP3R3V_FPGA

U38  TS3A5018PWR_TSSOP16  pkg SOP16_173_P0256  page 24
  1  \in\  BI  = MUX2_SEL
  2  NC1  BI  = FPGA_FLASH_CLK
  3  NO1  BI  = FT4232_SPI_CLK
  4  COM1  BI  = FLASH_CLK
  5  NC2  BI  = FPGA_FLASH_DQ0_MOSI
  6  NO2  BI  = FT4232_SPI_MOSI
  7  COM2  BI  = FLASH_DQ0_MOSI
  8  GND  GROUND  = SG
  9  COM3  BI  = FLASH_DQ1_MISO
  10  NO3  BI  = FT4232_SPI_MISO
  11  NC3  BI  = FPGA_FLASH_DQ1_MISO
  12  COM4  BI  = FLASH_CS_N
  13  NO4  BI  = FT4232_SPI_CS_N
  14  NC4  BI  = FPGA_FLASH_CS_N
  15  \en*\  BI  = UNNAMED_524_RESISTOR_I432_2
  16  V_P  POWER  = XP3R3V_FPGA

U39  NLASB3157DFT2G_SC88  pkg SOT363_V2  page 24
  1  B1  BI  = NC
  2  GND  GROUND  = SG
  3  B0  BI  = FLASH_DQ2
  4  A  BI  = FPGA_FLASH_DQ2
  5  VCC  POWER  = XP3R3V_FPGA
  6  \select\  BI  = MUX2_SEL

U40  NLASB3157DFT2G_SC88  pkg SOT363_V2  page 24
  1  B1  BI  = NC
  2  GND  GROUND  = SG
  3  B0  BI  = FLASH_DQ3
  4  A  BI  = FPGA_FLASH_DQ3
  5  VCC  POWER  = XP3R3V_FPGA
  6  \select\  BI  = MUX2_SEL

U41  ISL80101IRAJZ_DFN10  pkg DFN11_118_P0197_TR057X071  page 33
  1  VOUT_1  OUT  = XP3R3V_FT4232
  2  VOUT_2  OUT  = XP3R3V_FT4232
  3  \sense/adj\  BI  = UNNAMED_525_ISL80101IRAJZDFN10_
  4  PG  BI  = XP3R3V_FT_PG
  5  GND  GROUND  = SG
  6  SS  BI  = UNNAMED_525_CAPACITOR_I18_1
  7  ENABLE  BI  = UNNAMED_525_CAPACITOR_I14_1
  8  NC  NC  = NC
  9  VIN_1  IN  = UNNAMED_525_CAPACITOR_I16_1
  10  VIN_2  IN  = UNNAMED_525_CAPACITOR_I16_1
  11  THRM_PAD  GROUND  = SG

Y1  XTAL_2  pkg SMC_Y2_079X047  page 20 : 1 = UNNAMED_9_BNO080LGA28_I29_XOUT3 ; 2 = UNNAMED_9_CAPACITOR_I17_1

Y2  XTAL_4  pkg SMC_Y4_126X098_V5_H032  page 24
  1  \1\  UNSPEC  = UNNAMED_524_CAPACITOR_I7_2
  2  \2\  UNSPEC  = SG
  3  \3\  UNSPEC  = UNNAMED_524_CAPACITOR_I10_2
  4  \4\  UNSPEC  = SG

Y3  OSC6P_V2  pkg SMC_Y6_126X197  page 15
  1  OE  IN  = CLK_200M_OE
  2  NC  NC  = NC
  3  GND  GROUND  = SG
  4  OUT_P  OUT  = OSC_200M_CLKP
  5  OUT_N  OUT  = OSC_200M_CLKN
  6  VDD  POWER  = VDD3V3_OSC_200M

Y4  OSC6P_V2  pkg SMC_Y6_197X276  page 15
  1  OE  IN  = CLK_125M_OE
  2  NC  NC  = NC
  3  GND  GROUND  = SG
  4  OUT_P  OUT  = OSC_125M_CLKP
  5  OUT_N  OUT  = OSC_125M_CLKN
  6  VDD  POWER  = VDD3V3_OSC_125M
